(kicad_pcb
	(version 20241229)
	(generator "pcbnew")
	(generator_version "9.0")
	(general
		(thickness 1.63)
		(legacy_teardrops no)
	)
	(paper "A4")
	(title_block
		(title "CM4 Baseboard")
		(date "2026-01-05")
		(rev "1.1.1")
		(company "Antmicro Ltd")
		(comment 1 "www.antmicro.com")
		(comment 9 "footprints 344-348 of 506")
	)
	(layers
		(0 "F.Cu" signal)
		(4 "In1.Cu" power)
		(6 "In2.Cu" power)
		(8 "In3.Cu" signal)
		(10 "In4.Cu" signal)
		(2 "B.Cu" signal)
		(9 "F.Adhes" user "F.Adhesive")
		(11 "B.Adhes" user "B.Adhesive")
		(13 "F.Paste" user)
		(15 "B.Paste" user)
		(5 "F.SilkS" user "F.Silkscreen")
		(7 "B.SilkS" user "B.Silkscreen")
		(1 "F.Mask" user)
		(3 "B.Mask" user)
		(17 "Dwgs.User" user "User.Drawings")
		(19 "Cmts.User" user "User.Comments")
		(21 "Eco1.User" user "User.Eco1")
		(23 "Eco2.User" user "User.Eco2")
		(25 "Edge.Cuts" user)
		(27 "Margin" user)
		(31 "F.CrtYd" user "F.Courtyard")
		(29 "B.CrtYd" user "B.Courtyard")
		(35 "F.Fab" user)
		(33 "B.Fab" user)
	)
	(footprint "antmicro-footprints:R_0402_1005Metric"
		(layer "B.Cu")
		(at 56.167962 153.4165 -90)
		(descr "Resistor SMD 0402")
		(tags "resistor SMD 0402")
		(property "Reference" "R315"
			(at -2.995 -2.3 90)
			(layer "B.SilkS")
			(effects
				(font
					(size 0.7 0.7)
					(thickness 0.15)
				)
				(justify left bottom mirror)
			)
		)
		(property "Value" "R_100k_0402"
			(at -1.011843 -1.772047 90)
			(layer "B.Fab")
			(effects
				(font
					(size 0.7 0.7)
					(thickness 0.15)
				)
				(justify left bottom mirror)
			)
		)
		(property "Datasheet" "https://www.bourns.com/docs/product-datasheets/cr.pdf"
			(at 0 0 270)
			(layer "B.Fab")
			(hide yes)
			(effects
				(font
					(size 1.27 1.27)
					(thickness 0.15)
				)
			)
		)
		(property "Manufacturer" "Bourns"
			(at 0 0 270)
			(unlocked yes)
			(layer "B.Fab")
			(hide yes)
			(effects
				(font
					(size 1 1)
					(thickness 0.15)
				)
				(justify mirror)
			)
		)
		(property "MPN" "CR0402-FX-1003GLF"
			(at 0 0 270)
			(unlocked yes)
			(layer "B.Fab")
			(hide yes)
			(effects
				(font
					(size 1 1)
					(thickness 0.15)
				)
				(justify mirror)
			)
		)
		(property "Val" "100k"
			(at 0 0 270)
			(unlocked yes)
			(layer "B.Fab")
			(hide yes)
			(effects
				(font
					(size 1 1)
					(thickness 0.15)
				)
				(justify mirror)
			)
		)
		(property "License" "Apache-2.0"
			(at 0 0 270)
			(unlocked yes)
			(layer "B.Fab")
			(hide yes)
			(effects
				(font
					(size 1 1)
					(thickness 0.15)
				)
				(justify mirror)
			)
		)
		(property "Author" "Antmicro"
			(at 0 0 270)
			(unlocked yes)
			(layer "B.Fab")
			(hide yes)
			(effects
				(font
					(size 1 1)
					(thickness 0.15)
				)
				(justify mirror)
			)
		)
		(property "Tolerance" "1%"
			(at 0 0 270)
			(unlocked yes)
			(layer "B.Fab")
			(hide yes)
			(effects
				(font
					(size 1 1)
					(thickness 0.15)
				)
				(justify mirror)
			)
		)
		(sheetname "/Supply/")
		(sheetfile "supply.kicad_sch")
		(attr smd)
		(fp_rect
			(start -0.925 0.47)
			(end 0.925 -0.47)
			(stroke
				(width 0.05)
				(type default)
			)
			(fill no)
			(layer "B.CrtYd")
		)
		(fp_rect
			(start -0.5 0.25)
			(end 0.5 -0.25)
			(stroke
				(width 0.15)
				(type solid)
			)
			(fill no)
			(layer "B.Fab")
		)
		(fp_text user "${REFERENCE}"
			(at -0.95 -3.168 90)
			(layer "B.Fab")
			(effects
				(font
					(size 0.7 0.7)
					(thickness 0.15)
				)
				(justify left bottom mirror)
			)
		)
		(fp_text user "Author: Antmicro"
			(at -0.95 -4.169 90)
			(layer "B.Fab")
			(effects
				(font
					(size 0.7 0.7)
					(thickness 0.15)
				)
				(justify left bottom mirror)
			)
		)
		(fp_text user "License: Apache-2.0"
			(at -0.95 -5.169 90)
			(layer "B.Fab")
			(effects
				(font
					(size 0.7 0.7)
					(thickness 0.15)
				)
				(justify left bottom mirror)
			)
		)
		(pad "1" smd roundrect
			(at -0.48 0 270)
			(size 0.59 0.64)
			(layers "B.Cu" "B.Mask" "B.Paste")
			(roundrect_rratio 0.25)
			(net 66 "/Supply/VCC_5V")
			(pintype "passive")
		)
		(pad "2" smd roundrect
			(at 0.48 0 270)
			(size 0.59 0.64)
			(layers "B.Cu" "B.Mask" "B.Paste")
			(roundrect_rratio 0.25)
			(net 352 "Net-(U303-PG)")
			(pintype "passive")
		)
	)
	(footprint "antmicro-footprints:C_0805_2012Metric"
		(layer "B.Cu")
		(at 67.717962 158.1165 90)
		(descr "Capacitor SMD 0805")
		(tags "capacitor SMD 0805")
		(property "Reference" "C315"
			(at 0.88 2.9 90)
			(layer "B.SilkS")
			(effects
				(font
					(size 0.7 0.7)
					(thickness 0.15)
				)
				(justify right bottom mirror)
			)
		)
		(property "Value" "C_22u_25V_0805"
			(at -2.055717 -1.963152 90)
			(layer "B.Fab")
			(effects
				(font
					(size 0.7 0.7)
					(thickness 0.15)
				)
				(justify right bottom mirror)
			)
		)
		(property "Datasheet" "https://product.samsungsem.com/mlcc/CL21A226MAYNNN.do"
			(at 0 0 90)
			(layer "B.Fab")
			(hide yes)
			(effects
				(font
					(size 1.27 1.27)
					(thickness 0.15)
				)
			)
		)
		(property "Manufacturer" "Samsung Electro-Mechanics"
			(at 0 0 90)
			(unlocked yes)
			(layer "B.Fab")
			(hide yes)
			(effects
				(font
					(size 1 1)
					(thickness 0.15)
				)
				(justify mirror)
			)
		)
		(property "MPN" "CL21A226MAYNNNE"
			(at 0 0 90)
			(unlocked yes)
			(layer "B.Fab")
			(hide yes)
			(effects
				(font
					(size 1 1)
					(thickness 0.15)
				)
				(justify mirror)
			)
		)
		(property "Val" "22u"
			(at 0 0 90)
			(unlocked yes)
			(layer "B.Fab")
			(hide yes)
			(effects
				(font
					(size 1 1)
					(thickness 0.15)
				)
				(justify mirror)
			)
		)
		(property "License" "Apache-2.0"
			(at 0 0 90)
			(unlocked yes)
			(layer "B.Fab")
			(hide yes)
			(effects
				(font
					(size 1 1)
					(thickness 0.15)
				)
				(justify mirror)
			)
		)
		(property "Author" "Antmicro"
			(at 0 0 90)
			(unlocked yes)
			(layer "B.Fab")
			(hide yes)
			(effects
				(font
					(size 1 1)
					(thickness 0.15)
				)
				(justify mirror)
			)
		)
		(property "Voltage" "25V"
			(at 0 0 90)
			(unlocked yes)
			(layer "B.Fab")
			(hide yes)
			(effects
				(font
					(size 1 1)
					(thickness 0.15)
				)
				(justify mirror)
			)
		)
		(property "Dielectric" "X5R"
			(at 0 0 90)
			(unlocked yes)
			(layer "B.Fab")
			(hide yes)
			(effects
				(font
					(size 1 1)
					(thickness 0.15)
				)
				(justify mirror)
			)
		)
		(property "Public" "False"
			(at 0 0 90)
			(unlocked yes)
			(layer "B.Fab")
			(hide yes)
			(effects
				(font
					(size 1 1)
					(thickness 0.15)
				)
				(justify mirror)
			)
		)
		(sheetname "/Supply/")
		(sheetfile "supply.kicad_sch")
		(attr smd)
		(fp_line
			(start -0.3 -0.7)
			(end 0.3 -0.7)
			(stroke
				(width 0.15)
				(type solid)
			)
			(layer "B.SilkS")
		)
		(fp_line
			(start -0.3 0.7)
			(end 0.3 0.7)
			(stroke
				(width 0.15)
				(type solid)
			)
			(layer "B.SilkS")
		)
		(fp_rect
			(start 1.95 0.9)
			(end -1.95 -0.9)
			(stroke
				(width 0.05)
				(type default)
			)
			(fill no)
			(layer "B.CrtYd")
		)
		(fp_rect
			(start -0.95 0.675)
			(end 0.95 -0.675)
			(stroke
				(width 0.15)
				(type solid)
			)
			(fill no)
			(layer "B.Fab")
		)
		(fp_text user "${REFERENCE}"
			(at -1.9 -3.947 270)
			(layer "B.Fab")
			(effects
				(font
					(size 0.7 0.7)
					(thickness 0.15)
				)
				(justify left bottom mirror)
			)
		)
		(fp_text user "License: Apache-2.0"
			(at -1.9 -4.947 270)
			(layer "B.Fab")
			(effects
				(font
					(size 0.7 0.7)
					(thickness 0.15)
				)
				(justify left bottom mirror)
			)
		)
		(fp_text user "Author: Antmicro"
			(at -1.9 -5.947 270)
			(layer "B.Fab")
			(effects
				(font
					(size 0.7 0.7)
					(thickness 0.15)
				)
				(justify left bottom mirror)
			)
		)
		(pad "1" smd roundrect
			(at -1.1 0 90)
			(size 1.2 1.3)
			(layers "B.Cu" "B.Mask" "B.Paste")
			(roundrect_rratio 0.25)
			(net 77 "/Supply/OUT_5V")
			(pintype "passive")
		)
		(pad "2" smd roundrect
			(at 1.1 0 90)
			(size 1.2 1.3)
			(layers "B.Cu" "B.Mask" "B.Paste")
			(roundrect_rratio 0.25)
			(net 3 "GND")
			(pintype "passive")
		)
	)
	(footprint "antmicro-footprints:R_0402_1005Metric"
		(layer "B.Cu")
		(at 63.792962 161.2165)
		(descr "Resistor SMD 0402")
		(tags "resistor SMD 0402")
		(property "Reference" "R321"
			(at 13.445 0.73 0)
			(layer "B.SilkS")
			(effects
				(font
					(size 0.7 0.7)
					(thickness 0.15)
				)
				(justify right bottom mirror)
			)
		)
		(property "Value" "R_2k2_0402"
			(at -1.011843 -1.772047 0)
			(layer "B.Fab")
			(effects
				(font
					(size 0.7 0.7)
					(thickness 0.15)
				)
				(justify right bottom mirror)
			)
		)
		(property "Datasheet" "https://www.bourns.com/docs/product-datasheets/cr.pdf"
			(at 0 0 0)
			(layer "B.Fab")
			(hide yes)
			(effects
				(font
					(size 1.27 1.27)
					(thickness 0.15)
				)
			)
		)
		(property "MPN" "CR0402-FX-2201GLF"
			(at 0 0 0)
			(unlocked yes)
			(layer "B.Fab")
			(hide yes)
			(effects
				(font
					(size 1 1)
					(thickness 0.15)
				)
				(justify mirror)
			)
		)
		(property "Manufacturer" "Bourns"
			(at 0 0 0)
			(unlocked yes)
			(layer "B.Fab")
			(hide yes)
			(effects
				(font
					(size 1 1)
					(thickness 0.15)
				)
				(justify mirror)
			)
		)
		(property "License" "Apache-2.0"
			(at 0 0 0)
			(unlocked yes)
			(layer "B.Fab")
			(hide yes)
			(effects
				(font
					(size 1 1)
					(thickness 0.15)
				)
				(justify mirror)
			)
		)
		(property "Author" "Antmicro"
			(at 0 0 0)
			(unlocked yes)
			(layer "B.Fab")
			(hide yes)
			(effects
				(font
					(size 1 1)
					(thickness 0.15)
				)
				(justify mirror)
			)
		)
		(property "Val" "2k2"
			(at 0 0 0)
			(unlocked yes)
			(layer "B.Fab")
			(hide yes)
			(effects
				(font
					(size 1 1)
					(thickness 0.15)
				)
				(justify mirror)
			)
		)
		(property "Tolerance" "1%"
			(at 0 0 0)
			(unlocked yes)
			(layer "B.Fab")
			(hide yes)
			(effects
				(font
					(size 1 1)
					(thickness 0.15)
				)
				(justify mirror)
			)
		)
		(sheetname "/Supply/")
		(sheetfile "supply.kicad_sch")
		(attr smd)
		(fp_rect
			(start -0.925 0.47)
			(end 0.925 -0.47)
			(stroke
				(width 0.05)
				(type default)
			)
			(fill no)
			(layer "B.CrtYd")
		)
		(fp_rect
			(start -0.5 0.25)
			(end 0.5 -0.25)
			(stroke
				(width 0.15)
				(type solid)
			)
			(fill no)
			(layer "B.Fab")
		)
		(fp_text user "${REFERENCE}"
			(at -0.95 -3.168 180)
			(layer "B.Fab")
			(effects
				(font
					(size 0.7 0.7)
					(thickness 0.15)
				)
				(justify left bottom mirror)
			)
		)
		(fp_text user "License: Apache-2.0"
			(at -0.95 -5.169 180)
			(layer "B.Fab")
			(effects
				(font
					(size 0.7 0.7)
					(thickness 0.15)
				)
				(justify left bottom mirror)
			)
		)
		(fp_text user "Author: Antmicro"
			(at -0.95 -4.169 180)
			(layer "B.Fab")
			(effects
				(font
					(size 0.7 0.7)
					(thickness 0.15)
				)
				(justify left bottom mirror)
			)
		)
		(pad "1" smd roundrect
			(at -0.48 0)
			(size 0.59 0.64)
			(layers "B.Cu" "B.Mask" "B.Paste")
			(roundrect_rratio 0.25)
			(net 3 "GND")
			(pintype "passive")
		)
		(pad "2" smd roundrect
			(at 0.48 0)
			(size 0.59 0.64)
			(layers "B.Cu" "B.Mask" "B.Paste")
			(roundrect_rratio 0.25)
			(net 355 "/Supply/FB_3V3")
			(pintype "passive")
		)
	)
	(footprint "antmicro-footprints:Resonator_SMD_MicroCrystal_CM7V-T1A_3.2x1.5x0.65mm"
		(layer "B.Cu")
		(at 125.73 175.006 -90)
		(property "Reference" "Y802"
			(at -1.905 -0.889 180)
			(layer "B.SilkS")
			(effects
				(font
					(size 0.7 0.7)
					(thickness 0.15)
				)
				(justify left bottom mirror)
			)
		)
		(property "Value" "Resonator_32.768kHz_CM7V-T1A"
			(at -2 -2 90)
			(layer "B.Fab")
			(effects
				(font
					(size 0.7 0.7)
					(thickness 0.15)
				)
				(justify left bottom mirror)
			)
		)
		(property "Datasheet" "https://www.microcrystal.com/fileadmin/Media/Products/32kHz/Datasheet/CM7V-T1A.pdf"
			(at 0 0 90)
			(layer "B.Fab")
			(hide yes)
			(effects
				(font
					(size 1.27 1.27)
					(thickness 0.15)
				)
				(justify mirror)
			)
		)
		(property "Description" "Crystal, 32.768 kHz, SMD, 3.2mm x 1.5mm, 12.5 pF, 20 ppm, CC7V-T1A"
			(at 0 0 90)
			(layer "B.Fab")
			(hide yes)
			(effects
				(font
					(size 1.27 1.27)
					(thickness 0.15)
				)
				(justify mirror)
			)
		)
		(property "MPN" "CM7V-T1A-32.768kHz-12.5pF-20PPM-TC-QA"
			(at 0 0 270)
			(unlocked yes)
			(layer "B.Fab")
			(hide yes)
			(effects
				(font
					(size 1 1)
					(thickness 0.15)
				)
				(justify mirror)
			)
		)
		(property "Manufacturer" "Micro Crystal"
			(at 0 0 270)
			(unlocked yes)
			(layer "B.Fab")
			(hide yes)
			(effects
				(font
					(size 1 1)
					(thickness 0.15)
				)
				(justify mirror)
			)
		)
		(property "Val" "32.768 kHz"
			(at 0 0 270)
			(unlocked yes)
			(layer "B.Fab")
			(hide yes)
			(effects
				(font
					(size 1 1)
					(thickness 0.15)
				)
				(justify mirror)
			)
		)
		(property "Author" "Antmicro"
			(at 0 0 270)
			(unlocked yes)
			(layer "B.Fab")
			(hide yes)
			(effects
				(font
					(size 1 1)
					(thickness 0.15)
				)
				(justify mirror)
			)
		)
		(property "License" "Apache-2.0"
			(at 0 0 270)
			(unlocked yes)
			(layer "B.Fab")
			(hide yes)
			(effects
				(font
					(size 1 1)
					(thickness 0.15)
				)
				(justify mirror)
			)
		)
		(sheetname "/Peripherals/")
		(sheetfile "peripherals.kicad_sch")
		(attr smd)
		(fp_rect
			(start -1.85 1)
			(end 1.85 -1)
			(stroke
				(width 0.05)
				(type solid)
			)
			(fill no)
			(layer "B.CrtYd")
		)
		(fp_line
			(start -1.3 0.75)
			(end -1.6 0.4)
			(stroke
				(width 0.15)
				(type solid)
			)
			(layer "B.Fab")
		)
		(fp_line
			(start 1.6 0.75)
			(end -1.3 0.75)
			(stroke
				(width 0.15)
				(type solid)
			)
			(layer "B.Fab")
		)
		(fp_line
			(start -1.601 -0.748)
			(end -1.6 0.4)
			(stroke
				(width 0.15)
				(type solid)
			)
			(layer "B.Fab")
		)
		(fp_line
			(start -1.601 -0.748)
			(end 1.6 -0.748)
			(stroke
				(width 0.15)
				(type solid)
			)
			(layer "B.Fab")
		)
		(fp_line
			(start 1.6 -0.748)
			(end 1.6 0.75)
			(stroke
				(width 0.15)
				(type solid)
			)
			(layer "B.Fab")
		)
		(fp_text user "Author: Antmicro"
			(at -2 -6.4 90)
			(layer "B.Fab")
			(effects
				(font
					(size 0.7 0.7)
					(thickness 0.15)
				)
				(justify left bottom mirror)
			)
		)
		(fp_text user "License: Apache-2.0"
			(at -2 -4 90)
			(layer "B.Fab")
			(effects
				(font
					(size 0.7 0.7)
					(thickness 0.15)
				)
				(justify left bottom mirror)
			)
		)
		(fp_text user "${REFERENCE}"
			(at -2 -5.2 90)
			(layer "B.Fab")
			(effects
				(font
					(size 0.7 0.7)
					(thickness 0.15)
				)
				(justify left bottom mirror)
			)
		)
		(pad "1" smd roundrect
			(at -1.25 0 270)
			(size 1 1.8)
			(layers "B.Cu" "B.Mask" "B.Paste")
			(roundrect_rratio 0.1)
			(net 505 "Net-(U802-X1)")
			(pintype "passive")
		)
		(pad "2" smd roundrect
			(at 1.25 0 270)
			(size 1 1.8)
			(layers "B.Cu" "B.Mask" "B.Paste")
			(roundrect_rratio 0.1)
			(net 506 "Net-(U802-X2)")
			(pintype "passive")
		)
	)
	(footprint "antmicro-footprints:R_0402_1005Metric"
		(layer "B.Cu")
		(at 78.617962 146.5165 -90)
		(descr "Resistor SMD 0402")
		(tags "resistor SMD 0402")
		(property "Reference" "R411"
			(at -3.79 -0.41 90)
			(layer "B.SilkS")
			(effects
				(font
					(size 0.7 0.7)
					(thickness 0.15)
				)
				(justify left bottom mirror)
			)
		)
		(property "Value" "R_200R_0402"
			(at -1.011843 -1.772047 90)
			(layer "B.Fab")
			(effects
				(font
					(size 0.7 0.7)
					(thickness 0.15)
				)
				(justify left bottom mirror)
			)
		)
		(property "Datasheet" "https://www.bourns.com/docs/product-datasheets/cr.pdf"
			(at 0 0 270)
			(layer "B.Fab")
			(hide yes)
			(effects
				(font
					(size 1.27 1.27)
					(thickness 0.15)
				)
			)
		)
		(property "Manufacturer" "Bourns"
			(at 0 0 270)
			(unlocked yes)
			(layer "B.Fab")
			(hide yes)
			(effects
				(font
					(size 1 1)
					(thickness 0.15)
				)
				(justify mirror)
			)
		)
		(property "MPN" "CR0402-FX-2000GLF"
			(at 0 0 270)
			(unlocked yes)
			(layer "B.Fab")
			(hide yes)
			(effects
				(font
					(size 1 1)
					(thickness 0.15)
				)
				(justify mirror)
			)
		)
		(property "Val" "200R"
			(at 0 0 270)
			(unlocked yes)
			(layer "B.Fab")
			(hide yes)
			(effects
				(font
					(size 1 1)
					(thickness 0.15)
				)
				(justify mirror)
			)
		)
		(property "License" "Apache-2.0"
			(at 0 0 270)
			(unlocked yes)
			(layer "B.Fab")
			(hide yes)
			(effects
				(font
					(size 1 1)
					(thickness 0.15)
				)
				(justify mirror)
			)
		)
		(property "Author" "Antmicro"
			(at 0 0 270)
			(unlocked yes)
			(layer "B.Fab")
			(hide yes)
			(effects
				(font
					(size 1 1)
					(thickness 0.15)
				)
				(justify mirror)
			)
		)
		(property "Tolerance" "1%"
			(at 0 0 270)
			(unlocked yes)
			(layer "B.Fab")
			(hide yes)
			(effects
				(font
					(size 1 1)
					(thickness 0.15)
				)
				(justify mirror)
			)
		)
		(sheetname "/Ethernet/")
		(sheetfile "ethernet.kicad_sch")
		(attr smd)
		(fp_rect
			(start -0.925 0.47)
			(end 0.925 -0.47)
			(stroke
				(width 0.05)
				(type default)
			)
			(fill no)
			(layer "B.CrtYd")
		)
		(fp_rect
			(start -0.5 0.25)
			(end 0.5 -0.25)
			(stroke
				(width 0.15)
				(type solid)
			)
			(fill no)
			(layer "B.Fab")
		)
		(fp_text user "Author: Antmicro"
			(at -0.95 -4.169 90)
			(layer "B.Fab")
			(effects
				(font
					(size 0.7 0.7)
					(thickness 0.15)
				)
				(justify left bottom mirror)
			)
		)
		(fp_text user "${REFERENCE}"
			(at -0.95 -3.168 90)
			(layer "B.Fab")
			(effects
				(font
					(size 0.7 0.7)
					(thickness 0.15)
				)
				(justify left bottom mirror)
			)
		)
		(fp_text user "License: Apache-2.0"
			(at -0.95 -5.169 90)
			(layer "B.Fab")
			(effects
				(font
					(size 0.7 0.7)
					(thickness 0.15)
				)
				(justify left bottom mirror)
			)
		)
		(pad "1" smd roundrect
			(at -0.48 0 270)
			(size 0.59 0.64)
			(layers "B.Cu" "B.Mask" "B.Paste")
			(roundrect_rratio 0.25)
			(net 175 "Net-(J401-LED_YEL-)")
			(pintype "passive")
		)
		(pad "2" smd roundrect
			(at 0.48 0 270)
			(size 0.59 0.64)
			(layers "B.Cu" "B.Mask" "B.Paste")
			(roundrect_rratio 0.25)
			(net 212 "/Compute module/ETHERNET.LED_ACT")
			(pintype "passive")
		)
	)
)
